FILE_TYPE = MULTI_PHYS_TABLE;

PART 'NULL'
CLASS=MECHANICAL

{========================================================================================}
:CLS_PN              = DESCRIPTION                                                                            | CPN_STATUS ;
{========================================================================================}
 'G350-10098-01'     = 'MECH,CPU SOCKET BACKPLANE WITH H=6.33MM,FOR P0,LGA3647 NARROW'                        | ''        
 'G350-10099-01'     = 'MECH,NON-FABRIC PROCESSOR CLIP,FOR P0,LGA3647 NARROW'                                 | ''        
 'A350-00735-CL'     = 'MECH,CPU SOCKET BACKPLANE WITH H=7.35MM,FOR P0,LGA3647 NARROW'                        | ''        
 'G350-10096-01'     = 'MECH,FABRIC PROCESSOR CLIP,FOR P0,LGA3647 NARROW'                                     | ''        
 'G350-10097-01'     = 'MECH,CPU SOCKET FABRIC BOLSTER W/ DUST COVER,FOR P0,LGA3647 NARROW'                   | ''        
 'G350-10122-01'     = 'MECH,CPU SOCKET NON-FABRIC BOLSTER W/ DUST COVER,FOR P0,LGA3647 NARROW'               | ''        
 'G350-10123-01'     = 'MECH,NON-FABRIC PROCESSOR CLIP,FOR P0,LGA3647 NARROW'                                 | ''        
 'G350-10124-01'     = 'MECH,CPU SOCKET BACKPLANE WITH H=6.8MM,FOR P0,LGA3647 NARROW'                         | ''        
 'G350-10125-01'     = 'MECH,CPU SOCKET BACKPLANE WITH H=6.80MM,FOR P0,LGA3647 NARROW'                        | 'OBSOLETE'
 'R0987-E0009-01'    = 'MECH,PWR BUTTON CAP'                                                                  | ''        
 'R0987-E0008-01'    = 'MECH,ID BUTTON CAP'                                                                   | ''        
 'G350-10108-01'     = 'MECH,CPU SOCKET NON-FABRIC BOLSTER W/O DUST COVER,FOR P0,LGA3647 NARROW'              | ''        
 'G350-10118-01'     = 'MECH,CPU SOCKET BACKPLANE WITH H=7.66MM,FOR P0,LGA3647 NARROW'                        | ''        
 'G350-10120-01'     = 'MECH,CPU SOCKET NON-FABRIC BOLSTER W/ DUST COVER,FOR P0,LGA3647 NARROW'               | 'NFND'    
 'R0977-H0001-01'    = 'PGRM,AHTENA BIOS PROGRAM PART'                                                        | ''        
 'R0977-H0002-01'    = 'PGRM,AHTENA BMC PROGRAM PART'                                                         | ''        
 'R0977-H0003-01'    = 'PGRM,ATHENA CPLD PROGRAM PART'                                                        | ''        
 'R0977-H0004-01'    = 'PGRM,ATHENA PCIE SWITCH FW PROGRAM PART'                                              | ''        
 'R0977-H0005-01'    = 'PGRM,ATHENA CANISTER VPD PROGRAM PART'                                                | ''        
 'R0977-H0006-01'    = 'PGRM,ATHENA MID-PLANE VPD PROGRAM PART'                                               | ''        
 'R0977-H0007-01'    = 'PGRM,ATHEAN PHY EEPROM PROGRAM PART'                                                  | ''        
 'R0977-H0008-01'    = 'PGRM,ATHEAN PHY I210 EEPROM PROGRAM PART'                                             | ''        
 'R0977-H0009-01'    = 'PGRM,ATHENA CPLD BACKUP FLASH PROGRAM PART'                                           | ''        
 'R1111-E0001-02'    = 'MECH,MYLAR,SPARK 25G'                                                                 | ''        
 'R1111-E0003-02'    = 'MECH,MYLAR,SPARK 12G'                                                                 | ''        
 'R1111-E0002-02'    = 'MECH,MYLAR,SPARK 10G'                                                                 | ''        
 'R1092-E0010-01'    = 'MECH,MYLAR FOR OCP X557 CARD'                                                         | ''        
 'R1092-E0020-01'    = 'MECH,MYLAR FOR OCP CARD'                                                              | ''        
 'R1111-E0005-01'    = 'MECH,RUBBER 5MM,SPARK'                                                                | ''        
 'G380-10011-01'     = 'THERMAL GREASE-SHINETSU 7783D'                                                        | ''        
 'R1111-TP001-01'    = 'THERMAL PAD, CHOMERICS G974 SIZE 25*25 THICKNESS 0.25'                                | ''        
 'R1111-E0006-01'    = 'MECH,RUBBER 6MM,SPARK'                                                                | ''        
 'R1111-E0007-01'    = 'MECH,RUBBER 7MM,SPARK'                                                                | ''        
 'R1092-E0010-02'    = 'MECH,MYLAR FOR OCP X557 CARD'                                                         | ''        
 'R1092-E0021-01'    = 'MECH,MYLAR FOR OCP SFP+ CARD'                                                         | ''        
 'R1092-H0004-01'    = 'PRGM,ALDABRA X557-AT4 PHY SPI FLASH'                                                  | ''        
 'R1092-H0003-01'    = 'PRGM,ALDABRA X557-AT4 PHY ID EEPROM'                                                  | ''        
 'R1111-H0005-01'    = 'PRGM,SPARK OCP 10G FLASH'                                                             | ''        
 'R1111-H0004-01'    = 'PRGM,SPARK OCP 25G FLASH'                                                             | ''        
 'R1111-H0003-01'    = 'PRGM,SPARK 12G SAS I2C EEPROM'                                                        | ''        
 'R1111-H0006-01'    = 'PRGM,SPARK OCP 10G FLASH'                                                             | ''        
 'R1111-H0002-01'    = 'PRGM,OCP CARD VPD EEPROM'                                                             | ''        
 'R1111-H0001-01'    = 'PRGM,SPARK 12G SAS SPCV NOR FLASH'                                                    | ''        
 'R0977-H0009-02'    = 'PGRM,ATHENA CPLD BACKUP FLASH PROGRAM PART'                                           | ''        
 'R0977-H0006-02'    = 'PGRM,ATHENA MID-PLANE VPD PROGRAM PART'                                               | ''        
 'R0977-H0005-02'    = 'PGRM,ATHENA CANISTER VPD PROGRAM PART'                                                | ''        
 'R0977-H0004-02'    = 'PGRM,ATHENA PCIE SWITCH FW PROGRAM PART'                                              | ''        
 'R0977-H0003-02'    = 'PGRM,ATHENA CPLD PROGRAM PART'                                                        | ''        
 'R0977-H0002-02'    = 'PGRM,AHTENA BMC PROGRAM PART'                                                         | ''        
 'R0977-H0001-02'    = 'PGRM,AHTENA BIOS PROGRAM PART'                                                        | ''        
 'R1130-H0007-01'    = 'PRGM,FPGA,ETH SW EEPROM CONFIGURATION'                                                | ''        
 'R1111-E0013-01'    = 'MECH,EMC MYLAR,SPARK 12G'                                                             | ''        
 'R1111-E0006-02'    = 'MECH,RUBBER 6MM,SPARK'                                                                | ''        
 'R1111-E0008-01'    = 'MECH,TOP MYLAR,SPARK 12G'                                                             | ''        
 'R1111-E0005-02'    = 'MECH,RUBBER 5MM,SPARK'                                                                | ''        
 'R1111-E0010-01'    = 'MECH,TOP MYLAR,SPARK 25G'                                                             | ''        
 'R1111-E0012-01'    = 'MECH,EMC MYLAR,SPARK 10G'                                                             | ''        
 'R1111-E0009-01'    = 'MECH,TOP MYLAR,SPARK 10G'                                                             | ''        
 'R1111-E0007-02'    = 'MECH,RUBBER 7MM,SPARK'                                                                | ''        
 'R1111-E0011-01'    = 'MECH,WHITEBOX MYLAR,SPARK 25G'                                                        | ''        
 'R1130-H0004-01'    = 'PGRM, SPI FLASH,IC-U11'                                                               | ''        
 'R1130-H0003-01'    = 'PGRM, 10G SPI FLASH,IC-U13'                                                           | ''        
 'R1130-H0001-01'    = 'PGRM, VR IC-U3'                                                                       | ''        
 'R1130-H0002-01'    = 'PGRM, VR IC-U53'                                                                      | ''        
 'R1130-H0005-01'    = 'PGRM, CPLD,IC-U4'                                                                     | ''        
 'R1130-TP001-01'    = 'THERMAL PAD, SIZE 86.8*80 THICKNESS 1.5,SARCON GR-M'                                  | ''        
 'R1130-H0006-01'    = 'PGRM, 25G SPI FLASH,IC-U13'                                                           | ''        
 'R1130-H0008-01'    = 'PRGM,CPU CARD, EEPROM'                                                                | ''        
 'R1130-H0009-01'    = 'PRGM,25G NIC CX4 LAN SPI FLASH'                                                       | ''        
 'G350-10121-01'     = 'MECH,NON-FARBIC PROCESSOR CLIP,FOR P0,LGA3647 NARROW'                                 | ''        
 'R1136-H0006-01'    = 'PGRM,TITAN RBOD MB BMC FW'                                                            | ''        
 'R1136-H0005-01'    = 'PGRM,TITAN RBOD MB BIOS FW'                                                           | ''        
 'R1136-H0010-01'    = 'PGRM,TITAN SAS CARD FTXL710 FW'                                                       | ''        
 'R1136-H0008-01'    = 'PGRM,TITAN RBOD MB CPLD'                                                              | ''        
 'R1136-H0007-01'    = 'PGRM,TITAN RBOD MB I350 EEPROM FW'                                                    | ''        
 'R1136-H0015-01'    = 'PGRM,TITAN RBOD MB CPLD FOR 1U CONTROLLER'                                            | ''        
 'R1136-H0014-01'    = 'PGRM,TITAN RISER2 VPD'                                                                | ''        
 'R1136-H0017-01'    = 'PGRM,TITAN RBOD MB VPD FOR 1U CONTROLLER'                                             | ''        
 'R1136-H0016-01'    = 'PGRM,TITAN RBOD MB VPD'                                                               | ''        
 'R1136-H0013-01'    = 'PGRM,TITAN RISER1 VPD'                                                                | ''        
 'R1136-H0012-01'    = 'PGRM,TITAN BBU BOARD VPD'                                                             | ''        
 'R1136-H0011-01'    = 'PGRM,TITAN SAS CARD VPD'                                                              | ''        
 'R1136-H0009-01'    = 'PGRM,TITNA SAS CARD LSI3616 FW'                                                       | ''        
 'R1136-E0008-01'    = 'MECH,FOAM,SAS SFP LED,TITAN RBOD'                                                     | ''        
 'R1136-E0010-01'    = 'MECH,AIR SPONGE 2 FOR 2P,TITAN RBOD'                                                  | ''        
 'R0977-H3001-01'    = 'PGRM,ATHENA FOR WDC BIOS PROGRAM PART'                                                | ''        
 'R1130-TP002-01'    = 'THERMAL PAD, 90.4MM*80MM*1.5MM,SARCON GR-M'                                           | ''        
 'R1182-H0003-01'    = 'PGRM,CLARION CPLD PROGRAM PART'                                                       | ''        
 'R1182-H0006-01'    = 'PGRM,CLARION MID-PLANE VPD PROGRAM PART'                                              | ''        
 'R1182-H0009-01'    = 'PGRM,CLARION CPLD BACKUP FLASH PROGRAM PART'                                          | ''        
 'R1182-H0005-01'    = 'PGRM,CLARION CANISTER VPD PROGRAM PART'                                               | ''        
 'R1182-H0004-01'    = 'PGRM,CLARION PCIE SWITCH FW PROGRAM PART'                                             | ''        
 'R1182-H0002-01'    = 'PGRM,CLARION BMC PROGRAM PART'                                                        | ''        
 'R1182-H0001-01'    = 'PGRM,CLARION BIOS PROGRAM PART'                                                       | ''        
 'R1162-E0000-01'    = 'MECH,ATHENA-H_BUSBAR'                                                                 | ''        
 'R1140-H0009-01'    = 'PGRM,IBM_FAB3 CPLD BACKUP FLASH PROGRAM PART'                                         | ''        
 'R1140-H3009-01'    = 'PGRM,IBM_XIV CPLD BACKUP FLASH PROGRAM PART'                                          | ''        
 'R1130-H0011-01'    = 'PGRM, SPI FLASH,IC-U11 FPGA IMAGE FOR 10G MOC'                                        | ''        
 'R1130-H0010-01'    = 'PGRM, CPLD,IC-U4 FOR 10G MOC'                                                         | ''        
 'R1136-H0022-01'    = 'PGRM,TITAN RBOD MB BIOS FW FOR DDN'                                                   | ''        
 'R1225-H0003-01'    = 'PRGM,DDN_200NV CPLD PROGRAM PART'                                                     | ''        
 'R1225-H0001-01'    = 'PRGM,DDN_200NV BIOS PROGRAM PART'                                                     | ''        
 'R1225-H0009-01'    = 'PRGM,DDN_200NV CPLD BACKUP FLASH PROGRAM PART'                                        | ''        
 'R1225-H0006-01'    = 'PRGM,DDN_200NV MID-PLANE VPD PROGRAM PART'                                            | ''        
 'R1225-H0005-01'    = 'PRGM,DDN_200NV CANISTER VPD PROGRAM PART'                                             | ''        
 'R1140-H0002-01'    = 'PRGM,IBM_FAB3 BMC PROGRAM PART'                                                       | ''        
 'R1225-H0004-01'    = 'PRGM,DDN_200NV PCIE SWITCH FW PROGRAM PART'                                           | ''        
 'R0809-K0004-01'    = 'RESOLUTE 2.0,LED FOAM'                                                                | ''        
 'R1066-H0006-01'    = 'PRGM,TITAN,4U90 JBOD DC BOARD,VPD'                                                    | ''        
 'G380-10012-01'     = 'THERMAL GEL_T657 300CC CARTRIDGE'                                                     | ''        
 'R0987-H0019-01'    = 'PGRM,LOKI MB TI POWER FW_U50'                                                         | ''        
 'R0987-H0001-01'    = 'PGRM,LOKI BIOS'                                                                       | ''        
 'R0987-H0023-01'    = 'PGRM,LOKI MB TI POWER FW_U64'                                                         | ''        
 'R0988-H0001-01'    = 'PGRM,TYR BIOS'                                                                        | ''        
 'R0987-H0015-01'    = 'PGRM,LOKI MB VPD FRU FW'                                                              | ''        
 'R0987-H0021-01'    = 'PGRM,LOKI MB TI POWER FW_U56'                                                         | ''        
 'R0987-H0026-01'    = 'PGRM,LOKI MB TI POWER FW_U140'                                                        | ''        
 'R0987-H0017-01'    = 'PGRM,LOKI MB TI POWER FW_U34'                                                         | ''        
 'R0987-H0024-01'    = 'PGRM,LOKI MB TI POWER FW_U68'                                                         | ''        
 'R0987-H0022-01'    = 'PGRM,LOKI MB TI POWER FW_U60'                                                         | ''        
 'R0987-H0003-01'    = 'PGRM,LOKI BMC'                                                                        | ''        
 'R0987-H0002-01'    = 'PGRM,LOKI MB CPLD'                                                                    | ''        
 'R0987-H0020-01'    = 'PGRM,LOKI MB TI POWER FW_U53'                                                         | ''        
 'R0987-H0025-01'    = 'PGRM,LOKI MB TI POWER FW_U139'                                                        | ''        
 'R0987-H0018-01'    = 'PGRM,LOKI MB TI POWER FW_U43'                                                         | ''        
 'R0988-H0003-01'    = 'PGRM,TYR CPLD FW'                                                                     | ''        
 'R0977-H9008-01'    = 'PRGM, AHTENA VR FW U160 PROGRAM PART'                                                 | ''        
 'R0977-H9007-01'    = 'PRGM, AHTENA VR FW U43 PROGRAM PART'                                                  | ''        
 'R0977-H9006-01'    = 'PRGM, AHTENA VR FW U68 PROGRAM PART'                                                  | ''        
 'R0977-H9005-01'    = 'PRGM, AHTENA VR FW U64 PROGRAM PART'                                                  | ''        
 'R0977-H9004-01'    = 'PRGM, AHTENA VR FW U60 PROGRAM PART'                                                  | ''        
 'R0977-H9003-01'    = 'PRGM, AHTENA VR FW U56 PROGRAM PART'                                                  | ''        
 'R0977-H9002-01'    = 'PRGM, AHTENA VR FW U53 PROGRAM PART'                                                  | ''        
 'R0977-H9001-01'    = 'PRGM, AHTENA VR FW U50 PROGRAM PART'                                                  | ''        
 'R0987-H0006-01'    = 'PGRM,LOKI NVME RISER REDRIVER EEPROM'                                                 | ''        
 'R0988-H0014-01'    = 'PGRM,TYR LFF BACKPLANE CPLD'                                                          | ''        
 'R0988-H0012-01'    = 'PGRM,TYR X16 RISER2 CARD VPD'                                                         | ''        
 'R0988-H0006-01'    = 'PGRM,TYR X16 RISER VPD'                                                               | ''        
 'R0988-H0011-01'    = 'PGRM,TYR NVME SW BOARD EEPROM'                                                        | ''        
 'R0988-H0004-01'    = 'PGRM,TYR BACKPLANE CPLD'                                                              | ''        
 'R0988-H0008-01'    = 'PRGM,TYR X16+X8 RISER VPD'                                                            | ''        
 'R0988-H0005-01'    = 'PGRM,TYR X8 PASS THROUGH VPD'                                                         | ''        
 'R0988-H0007-01'    = 'PRGM,TYR X24 RISER VPD'                                                               | ''        
 'R1140-G0001-02-SC' = 'SCH,IBM_FAB3 MOTHER BOARD'                                                            | ''        
 'R0929-G0007-01-SC' = 'SCH,MP,EL LOBO 12G 2.5 INCH ERICSSON,SCHEMATIC'                                       | ''        
 'R1252-H0005-01'    = 'PRGM,TYR SE NVME BP BOARD CPLD'                                                       | ''        
 'R1252-H0002-01'    = 'PRGM,TYR SE BMC'                                                                      | ''        
 'R1252-H0001-01'    = 'PRGM,TYR SE BIOS'                                                                     | ''        
 'R1252-H0003-01'    = 'PRGM,TYR SE CPLD FW'                                                                  | ''        
 'R1252-H0004-01'    = 'PRGM,TYR SE MB VPD FRU FW'                                                            | ''        
 'R1048-H0008-01'    = 'PRGM,ULTRON SAS EXPANDER SES'                                                         | ''        
 'R1048-K0011-01'    = 'LABEL, PORT LABEL_2, ULTRON'                                                          | ''        
 'R1048-K0012-01'    = 'LABEL, PORT LABEL_3, ULTRON'                                                          | ''        
 'R1048-K0013-01'    = 'LABEL, PORT LABEL_4, ULTRON'                                                          | ''        
 'R1048-K0010-01'    = 'LABEL, PORT LABEL_1, ULTRON'                                                          | ''        
 'R1140-H1001-01'    = 'PRGM,IBM_FAB3 BIOS FOR CANISTER FRU 02PX429 PROGRAM PART'                             | ''        
 'R1140-H0001-01'    = 'PGRM,IBM_FAB3 BIOS PROGRAM PART'                                                      | ''        
 'G410-10056-01'     = 'LBL,AMI BMC ROYALTY LABEL FOR IBM ONLY'                                               | ''        
 'R1140-H0005-01'    = 'PGRM,IBM_FAB3 CANISTER VPD PROGRAM PART'                                              | ''        
 'R1140-H0004-01'    = 'PGRM,IBM_FAB3 PCIE SWITCH FW PROGRAM PART'                                            | ''        
 'R1140-H0003-01'    = 'PGRM,IBM_FAB3 CPLD PROGRAM PART'                                                      | ''        
 'R1140-H0006-01'    = 'PGRM,IBM_FAB3 MID-PLANE VPD PROGRAM PART'                                             | ''        
 'R1252-G0010-01-SC' = 'SCH,TYR SE MB SCHEMATIC'                                                              | ''        
 'R1252-G0019-01-SC' = 'SCH,TYR SE SAS EXPANDER CARD SCHEMATIC'                                               | ''        
 'R1252-G0001-01-SC' = 'SCH,TYR SE 2.5INCH 12SAS BP SCHEMATIC'                                                | ''        
 'R1252-G0002-01-SC' = 'SCH,TYR SE X16 TO 2X8 RISER SCHEMATIC'                                                | ''        
 'R1252-G0016-01-SC' = 'SCH,TYR SE X16 TO X16 RISER SCHEMATIC'                                                | ''        
 'R1252-G0015-01-SC' = 'SCH,TYR SE NVME X8 TO 2X4 PT CARD TX SCHEMATIC'                                       | ''        
 'R1252-G0003-01-SC' = 'SCH,TYR SE X24 TO 3X8 RISER SCHEMATIC'                                                | ''        
 'R1252-G0013-01-SC' = 'SCH,TYR SE 3.5INCH 12SAS BP SCHEMATIC'                                                | ''        
 'R1252-G0005-01-SC' = 'SCH,TYR SE FAN BOARD SCHEMATIC'                                                       | ''        
 'R1252-G0009-01-SC' = 'SCH,TYR SE NVME X8 TO 2X4 PT CARD SCHEMATIC'                                          | ''        
 'R1252-G0006-01-SC' = 'SCH,TYR SE 12NVME SW BOARD SCHEMATIC'                                                 | ''        
 'R1252-G0008-01-SC' = 'SCH,TYR SE X24 TO X8X16 RISER SCHEMATIC'                                              | ''        
 'R1252-G0007-01-SC' = 'SCH,TYR SE 12NVME BP SCHEMATIC'                                                       | ''        
 'R0977-E0019-01'    = 'MECH, FAB3 LED FOAM'                                                                  | ''        
 'R0977-E0020-01'    = 'MECH,ATHENA MP UPPER MYLAR'                                                           | ''        
 'R0977-E0021-01'    = 'MECH, ATHENA MP LOWER MYLAR'                                                          | ''        
 'R1140-H1004-01'    = 'PRGM,IBM_FAB3 PCIE SWITCH FW PROGRAM PART FOR FRU'                                    | ''        
 'R1240-B0005-02'    = 'PCB,PHALANX LINE CARD,430X280X3.5MM,18-LAYER,TU883,EING'                              | ''        
 'R1252-G0021-01-SC' = 'SCH,TYR SE OCP_C41C SCHEMATIC'                                                        | ''        
 'R1252-G0022-01-SC' = 'SCH,TYR SE OCP_C2XF SCHEMATIC'                                                        | ''        
 'R0987-H0011-01'    = 'PGRM,LOKI C41C MIZZ ID EEPROM'                                                        | ''        
 'R0987-H0012-01'    = 'PGRM,LOKI C2XF CS4227 EEPROM'                                                         | ''        
 'R0987-H0009-01'    = 'PGRM,LOKI C2XF MIZZ ID EEPROM'                                                        | ''        
 'R1267-G0001-01-SC' = 'SCH,FAB3S,MOTHERBOARD'                                                                | ''        
 'R1267-B0001-01'    = 'PCB,FAB3S,CONTROLLER BOARD,673MMX345MM,2.5MM,14L,IT170GRA1'                           | ''        
 'R1136-G0001-03-SC' = 'DOC,TITAN RBOD SERVER R1136-G0001-03 SCHEMATIC'                                       | ''        
 'R1136-G0009-03-SC' = 'DOC,TITAN RBOD CONTROLLER R1136-G0009-03 SCHEMATIC'                                   | ''        
 'R1136-G0029-01-SC' = 'DOC,TITAN RBOD CONTROLLER R1136-G0029-01 SCHEMATIC'                                   | ''        
 'R1136-G0003-03-SC' = 'DOC,TITAN RBOD SAS CARD R1136-G0003-03 SCHEMATIC'                                     | ''        
 'R1136-G0013-01-SC' = 'DOC,TITAN RBOD SAS CARD R1136-G0013-01 SCHEMATIC'                                     | ''        
 'R1136-G0023-01-SC' = 'DOC,TITAN RBOD SAS CARD R1136-G0023-01 SCHEMATIC'                                     | ''        
 'R1252-B0010-01'    = 'PCB,TYR SE MB,439.4MM*421.2MM,10L,1.9MM,NPG-150N'                                     | ''        
 'R1267-H0001-01'    = 'PRGM,IBM_FAB3S BIOS PROGRAM PART'                                                     | ''        
 'R1267-H0002-01'    = 'PRGM,IBM_FAB3S BMC PROGRAM PART'                                                      | ''        
 'R1267-H0003-01'    = 'PRGM,IBM_FAB3S CPLD PROGRAM PART'                                                     | ''        
 'R1267-H0009-01'    = 'PRGM,IBM_FAB3S CPLD BACKUP FLASH PROGRAM PART'                                        | ''        
 'R1140-G0003-01-SC' = 'SCH,IBM_FAB3 MIDPLANE BOARD'                                                          | ''        
 'R1252-B0002-01'    = 'PCB,TYR SE X16 TO 2X8 RISER,105MM*74MM,4L,1.6MM,EM285'                                | ''        
 'R1252-B0003-01'    = 'PCB,TYR SE X24 TO 3X8 RISER,130MM*65MM,6L,1.6MM,EM285'                                | ''        
 'R1252-B0005-01'    = 'PCB,TYR SE FAN BOARD,400MM*35.7MM,2L,1.6MM,IT158'                                     | ''        
 'R1066-G0013-02-SC' = 'SCH, TITAN LED BOARD SCHEMATIC'                                                       | ''        
 'R1252-B0019-01'    = 'PCB,TYR SE SAS EXPANDER CARD,167.65MM*68.9MM,8L,1.6 MM,TU862HF'                       | ''        
 'R1252-B0021-01'    = 'PCB,TYR SE OCP_C41C,107.2MM*71MM,8L,1.6MM,MIGTG FR4'                                  | ''        
 'R1252-B0022-01'    = 'PCB,TYR SE OCP_C2XF,110.1MM*71MM,8L,1.6MM,EM285'                                      | ''        
 'R1252-B0016-01'    = 'PCB,TYR SE X16 TO X16 RISER,105MM*74.4MM,4L,1.6MM,NPG-170N'                           | ''        
 'R1252-B0015-01'    = 'PCB,TYR SE NVME X8 TO 2X4 PT CARD TX,167.65MM*68.9MM,6L,1.6MM,NPG-170N'               | ''        
 'R1252-B0013-01'    = 'PCB,TYR SE 3.5INCH 12SAS BP,432MM*81MM,6L,2.4MM,EM285'                                | ''        
 'R1252-B0009-01'    = 'PCB,TYR SE NVME X8 TO 2X4 PT CARD,167.65MM*68.9MM,6L,1.6MM,NPG-170N'                  | ''        
 'R1252-B0008-01'    = 'PCB,TYR SE X24 TO X8X16 RISER,130.2MM*65MM,6L,1.6MM,NPG-170N'                         | ''        
 'R1252-B0007-01'    = 'PCB,TYR SE 12NVME BP,205.8MM*77.8MM,12L,1.8MM,NPG-170N'                               | ''        
 'R1252-B0006-01'    = 'PCB,TYR SE 12NVME SW BOARD,159MM*96MM,10L,1.9MM,NPG-170N'                             | ''        
 'R1252-B0001-01'    = 'PCB,TYR SE 2.5INCH 12SAS BP,211.3MM*77.8MM,12L,1.8MM,EM285'                           | ''        
 'R1263-HS070-01'    = 'HS,78MMX93.9MMX14.45MM,31_FINNS,COPPER,1 HEAT PIPES,GREASE AND PAD,SPRING SCREW,VCAA' | 'OBSOLETE'
 'R1263-HS069-01'    = 'HS,97MMX94.8MMX14.35MM,31_FINNS,COPPER,0 HEAT PIPES,GREASE AND PAD,SPRING SCREW,VCAA' | 'OBSOLETE'
 'R1263-H1001-01'    = 'PRGM, COLUMBUS VCAA SPI FLASH FOR BIOS'                                               | ''        
 'R0987-G0008-04-SC' = 'SCH,LOKI NVME BACKPLANE SCHEMATIC'                                                    | ''        
 'R0987-E0086-01'    = 'MECH,MYLAR FOR NVME BP,LOKI'                                                          | ''        
 'R0988-G0018-01-ME' = 'DOC,PCA,TYR NVME BP BOARD FOR WDC'                                                    | ''        
 'R0988-E0140-01'    = 'MECH,MYLAR FOR 2.5 BP UP,TYR'                                                         | ''        
 'R0987-E0085-01'    = 'MECH,MYLAR FOR BP,LOKI'                                                               | ''        
 'R0988-G0001-04-ME' = 'DOC,PCA,TYR BACKPLANE'                                                                | ''        
 'R0987-G0002-03-ME' = 'DOC,PCA,LOKI BACKPLANE'                                                               | ''        
 'R0987-G0008-04-ME' = 'DOC,PCA,LOKI NVME BACKPLANE'                                                          | ''        
 'R0988-G0013-01-ME' = 'DOC,PCA,TYR LFF BACKPLANE'                                                            | ''        
 'R0988-E0144-01'    = 'MECH,MYLAR FOR 3.5 BP,TYR'                                                            | ''        
 'R0988-E0142-01'    = 'MECH,MYLAR FOR 2.5 NVME BP UP,TYR'                                                    | ''        
 'R3007-G0001-01'    = 'PCA,IBM BLUE MOUNTAIN BBU BACKPLANE'                                                  | ''        
 'R3007-G0002-01'    = 'PCA,IBM BLUE MOUNTAIN PDB'                                                            | ''        
 'R0988-H0030-01'    = 'PRGM,TYR NVME SW BOARD EEPROM FOR 24P'                                                | ''        
 'R1267-H0006-01'    = 'PRGM,IBM_FAB3S MID-PLANE VPD PROGRAM PART'                                            | ''        
 'R1267-H0005-01'    = 'PRGM,IBM_FAB3S CANISTER VPD PROGRAM PART'                                             | ''        
 'R1263-H2001-01'    = 'PRGM, BIOS, R1263, COLUMBUS VCGA SPI FLASH BIOS'                                      | ''        
 'R1263-H2002-01'    = 'PRGM, VBIOS, R1263, COLUMBUS VCGA GPU VBIOS'                                          | ''        
 'R1263-H2003-01'    = 'PRGM, CPLD, R1263, COLUMBUS VCGA CPLD'                                                | ''        
 'R1136-H0034-01'    = 'PGRM,TITAN RBOD MB BMC FW FOR DDN'                                                    | ''        
 'R3007-H0002-01'    = 'PRGM,BLUE MOUNTAIN PDB VPD'                                                           | ''        
 'R3007-H0001-01'    = 'PRGM,BLUE MOUNTAIN BACKPLANE CPLD'                                                    | ''        
 'R3007-H0003-01'    = 'PRGM,BLUE MOUNTAIN BACKPLANE VPD'                                                     | ''        
 'R1263-HS073-01'    = 'HS,312.6MMX95.6MMX32MM,VC AND COPPER,SPRING SCREW,VCGA'                               | ''        
 'R1136-HS001-02'    = 'HS,108MMX78MMX25.5MM,33_FINNS,COPPER,3 HEAT PIPES,GREASE,SPRING SCREW'                | ''        
 'R1136-HS005-02'    = 'HS,138.5MMX149MMX25.5MM,33+29+24_FINNS,COPPER,3 HEAT PIPES,GREASE,SPRING SCREW'       | ''        
 'R0988-G0013-01-SC' = 'SCH,TYR LFF BP SCHEMATIC'                                                             | ''        
 'R0988-G0017-01-SC' = 'SCH,TYR MB WITH TI POWER SOLUTION_PCH 1G_NON FABRIC SCHEMATIC'                        | ''        
 'R0988-G0012-02-SC' = 'SCH,TYR MB WITH TI POWER SOLUTION AND PCH-4 SCHEMATIC'                                | ''        
 'R0988-G0018-01-SC' = 'SCH,TYR NVME BP BOARD FOR WDC SCHEMATIC'                                              | ''        
 'R0988-G0007-02-SC' = 'SCH,TYR NVME BP BOARD SCHEMATIC'                                                      | ''        
 'R0988-G0001-04-SC' = 'SCH,TYR BACKPLANE SCHEMATIC'                                                          | ''        
 'R1263-HS074-01'    = 'HS,312.6MMX95.6MMX32MM,COPPER,SPRING SCREW,VCGA COOLER,HEATSINK AND FAN'              | 'REJECTED'
 'R1252-H0006-01'    = 'PRGM,TYR SE 2.5 SAS BP BOARD CPLD'                                                    | ''        
 'R1252-H0007-01'    = 'PRGM,TYR SE 3.5 SAS BP BOARD CPLD'                                                    | ''        
 'G290-10007-01'     = 'BAT,3V,225MAH,-30 TO 70°C,CR2032'                                                     | ''        
 'R1136-E0001-01'    = 'MECH,SMT NUT M3L28'                                                                   | ''        
 'R1136-H0031-01'    = 'PGRM,TITAN RBOD SERVER POWER VR FW U53'                                               | ''        
 'R1136-H0029-01'    = 'PGRM,TITAN RBOD SERVER POWER VR FW U64'                                               | ''        
 'R1136-H0032-01'    = 'PGRM,TITAN RBOD SERVER POWER VR FW U43'                                               | ''        
 'R1136-H0030-01'    = 'PGRM,TITAN RBOD SERVER POWER VR FW U127'                                              | ''        
 'R1136-H0026-01'    = 'PGRM,TITAN RBOD CONTROLLER&SERVER POWER VR FW U56'                                    | ''        
 'R1136-H0028-01'    = 'PGRM,TITAN RBOD CONTROLLER&SERVER POWER VR FW U50'                                    | ''        
 'R1136-H0025-01'    = 'PGRM,TITAN RBOD CONTROLLER&SERVER POWER VR FW U34'                                    | ''        
 'G723-01007-01'     = 'SCREW,M3X0.5X6,PH,FLT,ST,ZC'                                                          | ''        
 'R1136-H0027-01'    = 'PGRM,TITAN RBOD CONTROLLER&SERVER POWER VR FW U114'                                   | ''        
 'R0977-E0091-01'    = 'MECH, TPM HOLDER'                                                                     | ''        
 'G330-10064-01'     = 'HS,DIMENSION 10MM*30MM*9MM,MATERIAL:AL,ADHESIVE HS'                                   | ''        
 'R3007-B0002-01'    = 'PCB,BLUE MOUNTAIN PDB,49MMX105MM,1.57MM,8L,TU862HF'                                   | ''        
 'R3007-B0001-01'    = 'PCB,BLUE MOUNTAIN,77.9MMX139.6MM,2.5MM,10L,TU862HF'                                   | ''        
 'R1136-F0040-01'    = 'ASSY,GASKET FOR 4SFP,TITAN RBOD'                                                      | ''        
 'R1136-HS006-01'    = 'HS,55MMX55MMX8MM,17_FINNS,ALUMINUM,PAD,PUSH PIN'                                      | ''        
 'R1147-HS031-01'    = 'HS,110MMX78MMX27MM,60_FINNS,ALUMINUM,3 HEAT PIPES,GREASE,SPRING SCREW'                | ''        
 'R3006-B0002-01'    = 'PCB,MEC SERVER,RISER BOARD,133.35MMX30.7MM,8L,TU862HF'                                | ''        
 'R3006-B0001-01'    = 'PCB,MEC SERVER,MOTHER BOARD,340.9MMX328.25MM,10L,TU862HF'                             | ''        
 'R3006-B0003-01'    = 'PCB,MEC SERVER,FAN BOARD,38.1MMX30.48MM,4L,TU862HF'                                   | ''        
 'R3006-G0001-01-SC' = 'SCH,R3006-G0001-01-SC,MEC SERVER,MB,REV01'                                            | ''        
 'R3006-G0002-01-SC' = 'SCH,R3006-G0002-01-SC,MEC SERVER,RISER CARD,REV01'                                    | ''        
 'R3006-G0003-01-SC' = 'SCH,R3006-G0003-01-SC,MEC SERVER,FAN BOARD,REV01'                                     | ''        
 'R3007-G0002-01-SC' = 'SCH,BLUE MOUNTAIN PDB SCHEMATIC'                                                      | ''        
 'R3007-G0001-01-SC' = 'SCH,BLUE MOUNTAIN BBU BACKPLANE SCHEMATIC'                                            | ''        
 'R0987-G0002-03-SC' = 'SCH,LOKI BACKPLANE SCHEMATIC'                                                         | ''        
 'R1267-H0004-01'    = 'PRGM,IBM_FAB3S PCIE SWITCH FW PROGRAM PART'                                           | ''        
 'R3042-G0001-01-SC' = 'SCH,IBM_FAB3+ MOTHER BOARD'                                                           | ''        
 'R3042-H0001-01'    = 'PRGM,IBM_FAB3+ BIOS PROGRAM PART'                                                     | ''        
 'R3042-H0013-01'    = 'PRGM,IBM_FAB3+ SVC PROGRAM PART'                                                      | ''        
 'R1136-H0035-01'    = 'PGRM,TITAN OCP_C41C VPD'                                                              | ''        
 'R1136-G0015-01-SC' = 'SCH,TITAN OCP_C41C SCHEMATIC'                                                         | ''        
 'R3006-H0001-01'    = 'PRGM,MEC SERVER BIOS CODE'                                                            | ''        
 'R3006-H0006-01'    = 'PRGM,MEC SERVER CS4223 EEPROM CODE'                                                   | ''        
 'R3006-H0002-01'    = 'PRGM,MEC SERVER BMC CODE'                                                             | ''        
 'R3006-H0005-01'    = 'PRGM,MEC SERVER I211 EEPROM CODE'                                                     | ''        
 'R3006-H0004-01'    = 'PRGM,MEC SERVER I210 EEPROM CODE'                                                     | ''        
 'R3006-H0003-01'    = 'PRGM,MEC SERVER CPLD CODE'                                                            | ''        
 'G350-10131-01'     = 'MECH,DUST COVER,LGA4189-4'                                                            | ''        
 'G350-10132-01'     = 'MECH,CARRIER-ICE LAKE,LGA4189-4'                                                      | ''        
 'G350-10133-01'     = 'MECH,CARRIER-COOPER LAKE,LGA4189-4'                                                   | ''        
 'G350-10134-01'     = 'MECH,BOLSTER PLATE W/O DUST COVER,LGA4189-4'                                          | ''        
 'G350-10135-01'     = 'MECH,BACK PLATE,LGA4189-4'                                                            | ''        
 'R3007-G0001-02-SC' = 'SCH,BLUE MOUNTAIN BBU BACKPLANE SCHEMATIC'                                            | ''        
 'R3006-H0009-01'    = 'PRGM,MEC SERVER VDDRB FIRMWARE CODE'                                                  | ''        
 'R3006-H0010-01'    = 'PRGM,MEC SERVER VCCIO FIRMWARE CODE'                                                  | ''        
 'R3006-H0008-01'    = 'PRGM,MEC SERVER VDDRA FIRMWARE CODE'                                                  | ''        
 'R3006-H0007-01'    = 'PRGM,MEC SERVER VCCIN FIRMWARE CODE'                                                  | ''        
 'R3006-H0011-01'    = 'PRGM,MEC SERVER VNN FIRMWARE CODE'                                                    | ''        
 'R0988-H0009-01'    = 'PGRM,TYR NVME BP BOARD CPLD'                                                          | ''        
 'R0988-H0013-01'    = 'PGRM,TYR OCP 25G EEPROM'                                                              | ''        
 'G340-10375-01'     = 'MECH,THUMB SCREW,MB,LOKI'                                                             | ''        
 'R1252-H0008-01'    = 'PRGM,TYR SE X24 TO 3X8 RISER VPD'                                                     | ''        
 'R1252-H0009-01'    = 'PRGM,TYR SE X24 TO X8X16 RISER VPD'                                                   | ''        
 'R1252-H0010-01'    = 'PRGM,TYR SE X16 TO 2X8 RISER VPD'                                                     | ''        
 'R1252-G0010-02-SC' = 'SCH,TYR SE MB SCHEMATIC'                                                              | ''        
 'R3042-H0002-01'    = 'PRGM,IBM_FAB3+ BMC PROGRAM PART'                                                      | ''        
 'R3042-H0005-01'    = 'PRGM,IBM_FAB3+ CANISTER VPD PROGRAM PART'                                             | ''        
 'R3042-H0004-01'    = 'PRGM,IBM_FAB3+ OSES PROGRAM PART'                                                     | ''        
 'R3006-G0004-01-SC' = 'SCH,R3006-G0004-01-SC,MEC SERVER,X710 CARD,REV01'                                     | ''        
 'R3006-H0012-01'    = 'PRGM,MEC SERVER I210_2 EEPROM CODE'                                                   | ''        
 'R1136-G0019-01-SC' = 'DOC,TITAN RBOD CONTROLLER R1136-G0019-01 SCHEMATIC'                                   | ''        
 'R3006-G0001-02-SC' = 'SCH,R3006-G0001-02-SC,MEC SERVER,MB'                                                  | ''        
 'R3006-G0002-02-SC' = 'SCH,R3006-G0002-02-SC,MEC SERVER,RISER BOARD'                                         | ''        
 'R3092-H0006-01'    = 'PRGM,SAPPHIRE BASE BOARD CPLD'                                                        | ''        
 'R3092-H0003-01'    = 'PRGM,SAPPHIRE BIOS FW'                                                                | ''        
 'R3092-H0002-01'    = 'PRGM,SAPPHIRE COME BOARD CPLD'                                                        | ''        
 'R3092-H0001-01'    = 'PRGM,SAPPHIRE COME BOARD VPD'                                                         | ''        
 'R3092-H0004-01'    = 'PRGM,SAPPHIRE BACK-UP BIOS FW'                                                        | ''        
 'R3092-H0005-01'    = 'PRGM,SAPPHIRE BASE BOARD VPD'                                                         | ''        
 'R3092-H0009-01'    = 'PRGM,SAPPHIRE BASE BOARD 88E6193 EEPROM FW'                                           | ''        
 'R3092-H0007-01'    = 'PRGM,SAPPHIRE BASE BOARD XL827 EEPROM FW'                                             | ''        
 'R3092-H0008-01'    = 'PRGM,SAPPHIRE BASE BOARD CEI0 EEPROM FW'                                              | ''        
 'R3092-H0010-01'    = 'PRGM,SAPPHIRE BASE BOARD CEI1 EEPROM FW'                                              | ''        
 'R3092-H0011-01'    = 'PRGM,SAPPHIRE BASE BOARD I210 EEPROM FW'                                              | ''        
 'R3092-G0002-01-SC' = 'SCH,SAPPHIRE BASE BOARD SCHEMATIC'                                                    | ''        
 'R3092-G0001-01-SC' = 'SCH,SAPPHIRE COME CARD SCHEMATIC'                                                     | ''        
 'R3006-H0013-01'    = 'PRGM,MEC SERVER X710 EEPROM CODE'                                                     | ''        
 '315-105776'        = 'IC,BRCM,BUNDLED,BCM56375*1+BCM84894M*3+BCM54998EM*5'                                  | ''        
 '315-105346'        = 'IC,BRCM,BUNDLED,BCM56375*1+BCM84894M*6'                                               | ''        
 '315-105314'        = 'IC,BRCM,BUNDLED,BCM56377*1+BCM54192*3'                                                | ''        
 '315-105313'        = 'IC,BRCM,BUNDLED,BCM56376*1+BCM54192*6'                                                | ''        
 '315-105312'        = 'IC,BRCM,BUNDLED,BCM56375*1+BCM82756*3+BCM54195*5'                                     | ''        
 'R3020-G0005-01-SC' = 'SCH,R3020-G0005-01-SC,TYR G2,X16 PCIE RETIMER CARD,REV01'                             | ''        
 'R3020-G0009-01-SC' = 'SCH,R3020-G0009-01-SC,TYR G2,OCP DUMMY CARD(WITH RETIMER IC),REV01'                   | ''        
 'R3020-G0004-01-SC' = 'SCH,R3020-G0004-01-SC,TYR G2,X8 PCIE RETIMER CARD,REV01'                              | ''        
 'R3020-G0010-01-SC' = 'SCH,R3020-G0010-01-SC,TYR G2,12*2.5INCH NVME MIDPLANE,REV01'                          | ''        
 'R3020-G0003-01-SC' = 'SCH,R3020-G0003-01-SC,TYR G2,2*2.5INCH REAR IO MIDPLANE,REV01'                        | ''        
 'R3092-F0004-01'    = 'SHANGHAI CHUYUE INDUSTRIAL CO LTD'                                                    | ''        
 'R3042-H0003-01'    = 'PRGM,IBM_FAB3+ CPLD PROGRAM PART'                                                     | ''        
 'R3092-H0012-01'    = 'PRGM,SAPPHIRE BASE BOARD DUMMY SFP+ MODULE 0XA0 FW'                                   | ''        
 'R3092-H0014-01'    = 'PRGM,SAPPHIRE BASE BOARD TLV EEPROM'                                                  | ''        
 'R3020-G0006-01-SC' = 'SCH,TYR GEN2 X32 TO X16/X8/X8 RISER CARD SCHEMATIC'                                   | ''        
 'R3020-G0008-01-SC' = 'SCH,TYR GEN2 X32 TO X16/X16 RISER CARD SCHEMATIC'                                     | ''        
 'R3020-G0002-01-SC' = 'SCH,TYR GEN2 3.5 INCH HYBRED BP SCHEMATIC'                                            | ''        
 'R3020-G0007-01-SC' = 'SCH,TYR GEN2 X16 TO X8/X8 RISER CARD SCHEMATIC'                                       | ''        
 'R1252-H0021-01'    = 'PRGM,TYR SE MB TI POWER FW_U34'                                                       | ''        
 'R1252-G0031-01-SC' = 'SCH,TYR SE 2.5INCH 12SAS BP FOR 8NVME SCHEMATIC'                                      | ''        
 'R3020-G0001-01-SC' = 'SCH,R3020-G0001-01-SC,TYR G2,MB'                                                      | ''        
 'R3020-H0001-01'    = 'PRGM,TYR GEN2 BIOS'                                                                   | ''        
 'R3020-H1007-01'    = 'PRGM,TYR GEN2 BMC'                                                                    | ''        
 'R1140-E0091-01'    = 'PLASTIC, TPM HOLDER,IBM BLUE'                                                         | ''        
 'R1140-D0011-01'    = 'PLAS,ATHENA SSD HOLDER,IBM BLUE'                                                      | ''        
 'R1136-G0034-02-SC' = 'SCH,TITAN RBOD DRIVE BOARD WO LED LCD SCHEMATIC'                                      | ''        
 'R1257-H0008-01'    = 'PRGM,SILVERSTONE DP SWITCH BOARD CPLD_2,LCMXO3LF-4300C-5BG400C,WITH IMAGE DVT'        | ''        
 'R1257-H0028-01'    = 'PRGM,SILVERSTONE DP SWITCH BOARD I120 EEPROM'                                         | ''        
 'R1257-H0007-01'    = 'PRGM,SILVERSTONE DP SWITCH BOARD CPLD_1,LCMXO3LF-4300C-5BG400C,WITH IMAGE DVT'        | ''        
 'R1257-H0011-01'    = 'PRGM,SILVERSTONE DP SWITCH BOARD CSD95480 WITH IMAGE DVT'                             | ''        
 'R1257-H0012-01'    = 'PRGM,SILVERSTONE DP SWITCH BOARD IR35215 WITH IMAGE FOR U87'                          | ''        
 'R1257-H0029-01'    = 'PRGM,SILVERSTONE DP SWITCH BOARD 128MB SPI FLASH'                                     | ''        
 'R1257-H0009-01'    = 'PRGM,SILVERSTONE DP SWITCH BOARD FPGA FLASH WITH IMAGE DVT'                           | ''        
 'R1257-H0013-01'    = 'PRGM,SILVERSTONE DP SWITCH BOARD IR35215 WITH IMAGE FOR U72'                          | ''        
 'R1257-H0030-01'    = 'PRGM,SILVERSTONE DP SWITCH BOARD BCM81724 EEPROM'                                     | ''        
 'R1257-H0010-01'    = 'PRGM,SILVERSTONE DP SWITCH BOARD UCD90120 WITH IMAGE DVT'                             | ''        
 'R1257-H0014-01'    = 'PRGM,SILVERSTONE DP SWITCH BOARD IR35215 WITH IMAGE FOR U45'                          | ''        
 'R0977-G0001-04-SC' = 'SCH,ATHENA MOTHER BOARD'                                                              | ''        
 'R3106-E0001-01'    = 'MECH,BBU POWER CONNECTOR 13.2*6.35'                                                   | ''        
 'R3106-H0001-01'    = 'PRGM,GROOT MB BIOS CODE'                                                              | ''        
 'R3106-H0012-01'    = 'PRGM,GROOT MB IO EXPANDER CODE'                                                       | ''        
 'R3106-G0001-01-SC' = 'SCH,GROOT MB SCHEMATIC,REV01'                                                         | ''        
 'R3106-H0002-01'    = 'PRGM,GROOT MB BIOS CODE'                                                              | ''        
 'R3106-H0003-01'    = 'PRGM,GROOT MB CPLD CODE'                                                              | ''        
 'R3106-H0004-01'    = 'PRGM,GROOT MB I210 EEPROM CODE'                                                       | ''        
 'R3106-H0005-01'    = 'PRGM,GROOT MB X557 EEPROM CODE'                                                       | ''        
 'R3106-H0006-01'    = 'PRGM,GROOT MB VPD'                                                                    | ''        
 'R3106-H0007-01'    = 'PRGM,GROOT MB PVCCIN FIRMWARE CODE'                                                   | ''        
 'R3106-H0008-01'    = 'PRGM,GROOT MB VDDQA FIRMWARE CODE'                                                    | ''        
 'R3106-H0009-01'    = 'PRGM,GROOT MB VDDQB FIRMWARE CODE'                                                    | ''        
 'R3106-H0010-01'    = 'PRGM,GROOT MB PVCCIO FIRMWARE CODE'                                                   | ''        
 'R3106-H0011-01'    = 'PRGM,GROOT MB PVNN FIRMWARE CODE'                                                     | ''        
 'R3006-H0017-01'    = 'PRGM,MEC SERVER X710 BOARD VPD'                                                       | ''        
 'R3006-H0016-01'    = 'PRGM,MEC SERVER FAN BOARD VPD'                                                        | ''        
 'R3006-H0014-01'    = 'PRGM,MEC SERVER MOTHER BOARD VPD'                                                     | ''        
 'R3006-H0015-01'    = 'PRGM,MEC SERVER RISER BOARD VPD'                                                      | ''        
 'R3106-H0013-01'    = 'PRGM,GROOT MB SES FIRMWARE'                                                           | ''        
 'R3106-H0014-01'    = 'PRGM,GROOT MB SES EEPROM'                                                             | ''        
 'R3040-H0006-01'    = 'PGRM,ATHENA+ MID-PLANE VPD PROGRAM PART'                                              | ''        
 'R3040-H0005-01'    = 'PGRM,ATHENA+ CANISTER VPD PROGRAM PART'                                               | ''        
 'R3040-G0001-01-SC' = 'SCH,ATHENA+ MOTHER BOARD'                                                             | ''        
 'R3006-G0005-01-SC' = 'SCH,R3006-G0005-01-SC,MEC SERVER,RISER CARD FOR 2ND PROPOSAL'                         | ''        
 'R3023-G0001-01-SC' = 'SCH,NEBULA GEN2 ESM SCHEMATIC'                                                        | ''        
 'R3023-G0002-01-SC' = 'SCH,NEBULA GEN2 SINGLE PORT MP SCHEMATIC'                                             | ''        
 'R3023-G0003-01-SC' = 'SCH,NEBULA GEN2 DUAL PORT MP SCHEMATIC'                                               | ''        
 'R3023-G0004-01-SC' = 'SCH,NEBULA GEN2 RISER CARD SCHEMATIC'                                                 | ''        
 'R3023-G0005-01-SC' = 'SCH,NEBULA GEN2 PASSTHROUGH CARD (WITH RETIMER) SCHEMATIC'                            | ''        
 'R3023-G0006-01-SC' = 'SCH,NEBULA GEN2 PASSTHROUGH CARD (WITHOUT RETIMER) SCHEMATIC'                         | ''        
 'R3023-G0008-01-SC' = 'SCH,NEBULA GEN2 BMC CARD SCHEMATIC'                                                   | ''        
 'R3023-G0009-01-SC' = 'SCH,NEBULA GEN2 HBA CARD SCHEMATIC'                                                   | ''        
 'R3106-D0001-01'    = 'PLAST,M2 HOLDER GROOT'                                                                | ''        
 'R3106-H0015-01'    = 'PRGM,GROOT MB CPLD BACKUP CODE'                                                       | ''        
 'R3006-G0002-03-SC' = 'SCH,R3006-G0002-03-SC,MEC SERVER,RISER BOARD'                                         | ''        
 'R3135-G0002-01-SC' = 'SCH,R3135-G0002-01-SC,ARES RISER CARD'                                                | ''        
 'R3135-G0001-01-SC' = 'SCH,R3135-G0001-01-SC,ARES MB'                                                        | ''        
 'R3135-H0001-01'    = 'PRGM,ARES BIOS CODE'                                                                  | ''        
 'R3135-H0002-01'    = 'PRGM,ARES BMC CODE'                                                                   | ''        
 'R3135-H0003-01'    = 'PRGM,ARES CPLD CODE'                                                                  | ''        
 'R3135-H0005-01'    = 'PRGM,ARES CS4223 EEPROM CODE'                                                         | ''        
 'R3135-H0006-01'    = 'PRGM,ARES VCCIN FIRMWARE CODE'                                                        | ''        
 'R3135-H0007-01'    = 'PRGM,ARES VDDRA FIRMWARE CODE'                                                        | ''        
 'R3135-H0004-01'    = 'PRGM,ARES I210 EEPROM CODE'                                                           | ''        
 'R3135-H0008-01'    = 'PRGM,ARES VDDRB FIRMWARE CODE'                                                        | ''        
 'R3135-H0009-01'    = 'PRGM,ARES VCCIO FIRMWARE CODE'                                                        | ''        
 'R3135-H0010-01'    = 'PRGM,ARES VNN FIRMWARE CODE'                                                          | ''        
 'R3106-G0002-01-SC' = 'SCH,GROOT RAISER CARD SCHEMATIC'                                                      | ''        
 'R3106-G0003-01-SC' = 'SCH,GROOT MB SCHEMATIC FOR LOW SKU'                                                   | ''        
 'G380-10013-01'     = 'ALPHA,SOLDER PREFORM,ALLOY SAC305,0603H'                                              | ''        
 'R3106-D0002-01'    = 'PLAST,IO LED COVER GROOT'                                                             | ''        
 'R3106-F0001-01'    = 'ASSY,CPU BACK PLATE GROOT'                                                            | ''        
 'R3023-E0012-01'    = 'MECH,NEBULA PASS THOUGH CARD LED FOAM'                                                | ''        
 'R3106-H0017-01'    = 'PRGM,GROOT HORNTAIL VPD'                                                              | ''        
 'R3106-H0016-01'    = 'PRGM,GROOT RIDGEBACK VPD'                                                             | ''        
 'R3135-G0001-02-SC' = 'SCH,R3135-G0001-02-SC,ARES MB'                                                        | ''        
 'R3042-H0008-01'    = 'PRGM,IBM_FAB3+ OSES PROGRAM PART FOR SYSTEM AND TAA'                                  | ''        
 'R3160-G0006-01-SC' = 'SCH,FB CLOUDRIPPER PDB-B SCHEMATIC'                                                   | ''        
 'R3160-G0005-01-SC' = 'SCH,FB CLOUDRIPPER PDB-T SCHEMATIC'                                                   | ''        
 'R3160-G0001-01-SC' = 'SCH,FB CLOUDRIPPER SMB SCHEMATIC'                                                     | ''        
 'R3042-H0011-01'    = 'PRGM,IBM_FAB3+ BIOS PROGRAM PART FOR CANISTER FRU'                                    | ''        
 'R3106-F0023-01'    = 'ASSY,CPU BACK PLATE WITH HOLE GROOT'                                                  | ''        
 'R3106-HS140-01'    = 'HS,58MM*8MM*25MM,17 FINS,ALUMINMUM,PAD,COPPER PUSH PIN'                               | ''        
 'R3106-HS139-01'    = 'HS,40MMX40MMX8MM,PIN FIN 15X4 ARRAY,ALUMINMUM,COPPER PUSH PIN'                        | ''        
 'R3106-HS138-01'    = 'HS,41MMX38MMX25MM,PIN FIN 12X4 ARRAY,ALUMINMUM,COPPER PUSH PIN'                       | ''        
 'R3139-G0001-01-SC' = 'SCH,ATHENA GEN2,MB'                                                                   | ''        
 'R3023-H0001-01'    = 'PRGM,NEBULA GEN2 PEX88080 SES F/W'                                                    | ''        
 'R3135-H0011-01'    = 'PRGM,ARES MOTHER BOARD VPD'                                                           | ''        
 'R3135-H0013-01'    = 'PRGM,ARES FAN BOARD VPD'                                                              | ''        
 'R3135-H0012-01'    = 'PRGM,ARES RISER BOARD VPD'                                                            | ''        
 'R3135-G0003-01-SC' = 'SCH,R3135-G0003-01-SC,ARES,FAN BOARD'                                                 | ''        
 'R3106-G0003-02-SC' = 'SCH,GROOT MB DVT SCHEMATIC FOR LOW SKU'                                               | ''        
 'R3106-G0001-02-SC' = 'SCH,GROOT MB DVT SCHEMATIC FOR HIGH SKU'                                              | ''        
 'R3106-E0008-01'    = 'MECH,CANISTER PCBA SUPPORT FOAM1 GROOT'                                               | ''        
 'R3106-E0009-01'    = 'MECH,CANISTER PCBA SUPPORT FOAM2 GROOT'                                               | ''        
 'R3160-H0001-01'    = 'PRGM,ONLINE AND OFFLINE CODES ARE SAME,CLOUDRIPPER SDK IMAGE'                         | ''        
 'R3160-H0002-01'    = 'PRGM,ONLINE AND OFFLINE CODES ARE SAME,CLOUDRIPPER BMC IMAGE'                         | ''        
 'R3006-G0004-02-SC' = 'SCH,R3006-G0004-02-SC,MEC SERVER,X710 BOARD'                                          | ''        
 'R3006-G0001-03-SC' = 'SCH,R3006-G0001-03-SC,MEC SERVER,MB'                                                  | ''        
 'R3135-G0005-01-SC' = 'SCH,R3135-G0005-01-SC,ARES,1PPS&TOD BOARD'                                            | ''        
 'R3023-G0012-01-SC' = 'SCH,NEBULA GEN2 ESM WITH MICROSEMI SWITCH SCHEMATIC'                                  | ''        
 'R3023-G0011-01-SC' = 'SCH,NEBULA GEN2 HBA CARD WITH MICROSEMI SWITCH SCHEMATIC'                             | ''        
 'R3139-E0021-01'    = 'MECH,ATHENA GEN2 MP LOWER MYLAR'                                                      | ''        
 'R3139-E0020-01'    = 'MECH,ATHENA GEN2 MP UPPER MYLAR'                                                      | ''        
 'R3006-H0018-01'    = 'PRGM,MEC SERVER RESPIN MOTHER BOARD VPD'                                              | ''        
 'R3139-G0004-01-SC' = 'SCH,ATHENA GEN2 RISER CARD BOARD'                                                     | ''        
 'R3139-G0002-01-SC' = 'SCH,ATHENA GEN2 MIDPLANE BOARD'                                                       | ''        
 'R3139-G0003-01-SC' = 'SCH,ATHENA GEN2 PIB BOARD'                                                            | ''        
 'R3139-H0001-01'    = 'PRGM,ATHENAN GEN2 BIOS PROGRAM PART'                                                  | ''        
 'R3139-H0002-01'    = 'PRGM,ATHENAN GEN2 BMC PROGRAM PART'                                                   | ''        
 'R3139-H0003-01'    = 'PRGM,ATHENAN GEN2 CPLD PROGRAM PART'                                                  | ''        
 'R3139-H0004-01'    = 'PRGM,ATHENAN GEN2 PCIE SWITCH FW PROGRAM PART'                                        | ''        
 'R3139-H0005-01'    = 'PRGM,ATHENAN GEN2 CANISTER VPD PROGRAM PART'                                          | ''        
 'R3139-H0006-01'    = 'PRGM,ATHENAN GEN2 MID-PLANE VPD PROGRAM PART'                                         | ''        
 'R3139-H0007-01'    = 'PRGM,ATHENAN GEN2 PIB VPD PROGRAM PART'                                               | ''        
 'R3139-H0008-01'    = 'PRGM,ATHENAN GEN2 XGNIC FW PROGRAM PART'                                              | ''        
 'R3139-H0009-01'    = 'PRGM,ATHENAN GEN2 EEPROM PROGRAM PART'                                                | ''        
 'R3139-H0010-01'    = 'PRGM,ATHENAN GEN2 CPUIN VR PROGRAM PART'                                              | ''        
 'R3139-H0011-01'    = 'PRGM,ATHENAN GEN2 VCCIO VR PROGRAM PART'                                              | ''        
 'R3139-H0012-01'    = 'PRGM,ATHENAN GEN2 VDDQ VR PROGRAM PART'                                               | ''        
 'R3139-H0013-01'    = 'PRGM,ATHENAN GEN2 PEX0V9 VR PROGRAM PART'                                             | ''        
 'R3139-H0014-01'    = 'PRGM,ATHENA GEN2 CPLD BACKUP PROGRAM PART'                                            | ''        
 'R3023-H0010-01'    = 'PRGM,NEBULA GEN2 PM41084 SES F/W'                                                     | ''        
 'R3006-G0001-04-SC' = 'SCH,R3006-G0001-04-SC,MEC SERVER,MB,D-2145NT'                                         | ''        
 'R3006-H0019-01'    = 'PRGM,MEC SERVER LOW COST MOTHER BOARD VPD'                                            | ''        
 'G350-10141-01'     = 'MECH,CPU SOCKET BOLSTER W/ DUST COVER,LGA4677'                                        | ''        
 'G350-10143-01'     = 'MECH,CPU CARRIER E1A,LGA4677'                                                         | ''        
 'G350-10142-01'     = 'MECH,CPU SOCKET BACKPLANE WITH H=8.3MM,LGA4677'                                       | ''        
 'R3023-G0013-01-SC' = 'SCH,NEBULA GEN2 PASSTHROUGH CARD (WITH NEW RETIMER) SCHEMATIC'                        | ''        
 'R3023-G0014-01-SC' = 'SCH,NEBULA GEN2 PASSTHROUGH CARD (WITH ASTERA RETIMER) SCHEMATIC'                     | ''        
 'R3160-G0001-02-SC' = 'SCH,FB CLOUDRIPPER SMB SCHEMATIC'                                                     | ''        
 'R3023-H0008-01'    = 'PRGM,NEBULA GEN2 RETIMER 4X4 CONFIG EEPROM'                                           | ''        
 'R3137-G0001-01-SC' = 'SCH,TITAN G2 ESM PCBA SCHEMATIC'                                                      | ''        
 'R3137-H0004-01'    = 'PRGM,TITAN G2 ESM VPD FW'                                                             | ''        
 'R3137-H0003-01'    = 'PRGM,TITAN G2 ESM CPLD1 FW'                                                           | ''        
 'R3137-H0001-01'    = 'PRGM,TITAN G2 ESM SES FW'                                                             | ''        
 'R1066-E0011-01'    = 'MECH,BRKT,PRESS MINISAS,TITAN'                                                        | ''        
 'R3167-H0001-01'    = 'PRGM,RACCOON BIOS CODE'                                                               | ''        
 'R3137-H0002-01'    = 'PRGM,TITAN G2 ESM CPLD0 FW'                                                           | ''        
 'R3106-G0001-03-SC' = 'SCH,GROOT MB HIGH SKU FOR PVT'                                                        | ''        
 'R3106-G0003-03-SC' = 'SCH,GROOT MB LOW SKU FOR PVT'                                                         | ''        
 'R3139-G0001-02-SC' = 'SCH,ATHENA GEN2 DVT MB'                                                               | ''        
 'R3139-G0005-01-SC' = 'SCH,ATHENA GEN2 TPM CARD,EVT'                                                         | ''        
 'R3023-G0008-02-SC' = 'SCH,NEBULA GEN2 BMC2500 CARD SCHEMATIC,DVT'                                           | ''        
 'R3139-H0015-01'    = 'PRGM,ATHENA GEN2 I210IS FW PROGRAM PART'                                              | ''        
 'R3137-G0001-02-SC' = 'SCH,TITAN SAS4 ESM PCBA SCHEMATIC,A2'                                                 | ''        
 'R3106-F0023-02'    = 'ASSY,CPU BACK PLATE WITH HOLE CUSTOMIZE STUD GROOT'                                   | ''        
 'R1149-H0014-03'    = 'PRGM,WEDGE400,SMB,OOB_BCM5389'                                                        | ''        
 'R3116-G0001-01-SC' = 'SCH,FAB4 MB SCHEMATIC'                                                                | ''        
 'R3116-G0007-01-SC' = 'SCH,FAB4 PCIE ADAPTER CARD BOARD'                                                     | ''        
 'R3116-G0003-01-SC' = 'SCH,FAB4 FS9K DRIVE MIDPLANE SCHEMATIC'                                               | ''        
 'R3116-G0004-01-SC' = 'SCH,FAB4 SVC-H 2U MIDPLANE SCHEMATIC'                                                 | ''        
 'R3116-G0005-01-SC' = 'SCH,FAB4 FS9K PSU BACKPLANE SCHEMATIC'                                                | ''        
 'R3116-G0006-01-SC' = 'SCH,FAB4 SVC-H 2U PSU BACKPLANE'                                                      | ''        
 'R3116-G0008-01-SC' = 'SCH,FAB4 PIB SCHEMATIC'                                                               | ''        
 'R3116-G0009-01-SC' = 'SCH,FAB4 M.2 ADAPTER BOARD SCHEMATIC'                                                 | ''        
 'R3116-G0010-01-SC' = 'SCH,FAB4 BBU BACKPLANE SCHEMATIC'                                                     | ''        
 'R3249-G0001-01-SC' = 'SCH,COMBA 2U EDGE MB SCHEMATIC,A1'                                                    | ''        
 'R3249-G0002-01-SC' = 'SCH,COMBA 2U EDGE X32 TO X16X16 RISER SCHEMATIC,A1'                                   | ''        
 'R3249-G0004-01-SC' = 'SCH,COMBA 2U EDGE FAN BOARD SCHEMATIC,A1'                                             | ''        
 'R3249-G0003-01-SC' = 'SCH,COMBA 2U EDGE PIB SCHEMATIC,A1'                                                   | ''        
 'R3023-E0012-02'    = 'MECH,NEBULA PASS THOUGH CARD LED FOAM'                                                | ''        
 'R3116-E0207-01'    = 'MECH,BP INSULATOR1 TOP1 FAB4 2U'                                                      | ''        
 'R3116-E0206-01'    = 'MECH,BP INSULATOR1 BTM1 FAB4 2U'                                                      | ''        
 'R3116-H0002-01'    = 'PRGM,FAB4 PCIE SWITCH PSX PROGRAM PART'                                               | ''        
 'R3116-H0008-01'    = 'PRGM,FAB4 2U CANISTER VPD PROGRAM PART'                                               | ''        
 'R3116-H0007-01'    = 'PRGM,FAB4 4U CANISTER VPD PROGRAM PART'                                               | ''        
 'R3116-E0168-01'    = 'MECH,MB BOTTOM FOAM FOR THERMAL,FAB4'                                                 | ''        
 'R3116-E0169-01'    = 'MECH,PCIE PCBA FOAM,FAB4'                                                             | ''        
 'R3116-E0167-01'    = 'MECH,MB TOP FOAM FOR THERMAL,FAB4'                                                    | ''        
 'R3116-E0170-01'    = 'MECH,MP MYLAR,FAB4'                                                                   | ''        
 'R3023-G0009-02-SC' = 'SCH,NEBULA GEN2 HBA CARD SCHEMATIC'                                                   | ''        
 'R3023-G0001-02-SC' = 'SCH,NEBULA GEN2 ESM SCHEMATIC'                                                        | ''        
 'R3139-G0001-12-SC' = 'SCH,ATHENA GEN2 DVT SCH WITH TI POWER SOLUTION'                                       | ''        
 'R3116-H0001-01'    = 'PRGM,FAB4 PCIE SWITCH PFX PROGRAM PART'                                               | ''        
 'R3116-E0401-01'    = 'MECH,MYLAR,FAB4 MB FRONT 240V MYLAR'                                                  | ''        
 'R3116-E0402-01'    = 'MECH,MYLAR,FAB4 MB REAR 240V MYLAR'                                                   | ''        
 'R3235-G0001-01-SC' = 'SCH,SILVERSTONE3A SW BOARD PCBA SCHEMATIC'                                            | ''        
 'R3235-G0023-01-SC' = 'SCH,SILVERSTONE3A FRONT PANEL BOARD PCBA SCHEMATIC'                                   | ''        
 'R3235-G0002-01-SC' = 'SCH,SILVERSTONE3A POWER-TEST BOARD PCBA SCHEMATIC'                                    | ''        
 'R3160-G0001-03-SC' = 'SCH,FB CLOUDRIPPER SMB SCHEMATIC'                                                     | ''        
 'R3116-E0208-01'    = 'MECH,SYSTEM LED FOAM FAB4'                                                            | ''        
 'R3116-D0005-01'    = 'PLAST,MYLAR HDD BP BOTTOM'                                                            | ''        
 'R3116-D0003-01'    = 'PLAST,MYLAR HDD BP TOP'                                                               | ''        
 'R3116-D0004-01'    = 'PLAST,MYLAR HDD BP MID'                                                               | ''        
 'R3116-G0002-01-SC' = 'SCH,FAB4 MB SVC SCHEMATIC'                                                            | ''        
 'R3006-G0001-05-SC' = 'SCH,R3006-G0001-05-SC,MEC SERVER,MB'                                                  | ''        
 'R3139-H0016-01'    = 'PRGM,OFFLINE,ATHENA GEN2 VR U46'                                                      | ''        
 'R3139-H0023-01'    = 'PRGM,OFFLINE,ATHENA GEN2 VR U196'                                                     | ''        
 'R3139-H0022-01'    = 'PRGM,OFFLINE,ATHENA GEN2 VR U195'                                                     | ''        
 'R3139-H0021-01'    = 'PRGM,OFFLINE,ATHENA GEN2 VR U194'                                                     | ''        
 'R3139-H0020-01'    = 'PRGM,OFFLINE,ATHENA GEN2 VR U193'                                                     | ''        
 'R3139-H0019-01'    = 'PRGM,OFFLINE,ATHENA GEN2 VR U34'                                                      | ''        
 'R3139-H0018-01'    = 'PRGM,OFFLINE,ATHENA GEN2 VR U192'                                                     | ''        
 'R3139-H0017-01'    = 'PRGM,OFFLINE,ATHENA GEN2 VR U159'                                                     | ''        
 'R3023-H0001-02'    = 'PRGM,NEBULA GEN2 PEX88080 SES F/W,V02'                                                | ''        
 'R3023-H0005-01'    = 'PRGM,NEBULA GEN2 HBA PEX88032 SES F/W,V01'                                            | ''        
 'R3023-H0003-01'    = 'PRGM,NEBULA GEN2 CPLD F/W,V01'                                                        | ''        
 'R3023-H0002-01'    = 'PRGM,NEBULA GEN2 ESM BOARD VPD,V01'                                                   | ''        
 'R3023-H0009-01'    = 'PRGM,NEBULA2 DUAL PORT MIDPLANE VPD,V01'                                              | ''        
 'R3116-H0003-01'    = 'PRGM,FAB4 FS9K/SVC MB CPLD1 PRIMARY PROGRAM PART'                                     | ''        
 'R3116-H0004-01'    = 'PRGM,FAB4 FS9K MB CPLD2 PRIMARY PROGRAM PART'                                         | ''        
 'R3116-H0005-01'    = 'PRGM,FAB4 FS9K/SVC MB BIOS PROGRAM PART'                                              | ''        
 'R3116-H0009-01'    = 'PRGM,FAB4 FS9K MID-PLANE VPD PROGRAM PART'                                            | ''        
 'R3116-H0010-01'    = 'PRGM,FAB4 SVC MID-PLANE VPD PROGRAM PART'                                             | ''        
 'R3116-H0011-01'    = 'PRGM,FAB4,PCIE ADAPTER CARD VPD PROGRAM PART'                                         | ''        
 'R3116-H0013-01'    = 'PRGM,FAB4 FS9K MB CPLD2 BACKUP PROGRAM PART'                                          | ''        
 'R3116-H0015-01'    = 'PRGM,FAB4 SVC MB CPLD2 PRIMARY PROGRAM PART'                                          | ''        
 'R3116-H0016-01'    = 'PRGM,FAB4 FS9K/SVC MB CPLD1 BACKUP PROGRAM PART'                                      | ''        
 'R3116-H0017-01'    = 'PRGM,FAB4 SVC MB CPLD2 BACKUP PROGRAM PART'                                           | ''        
 'R3116-H0018-01'    = 'PRGM,FAB4,FS9K/SVC MB PVCCIN_CPU0 VR PROGRAM PART'                                    | ''        
 'R3116-H0019-01'    = 'PRGM,FAB4,FS9K/SVC MB PVCCIO_CPU0 VR PROGRAM PART'                                    | ''        
 'R3116-H0020-01'    = 'PRGM,FAB4,FS9K/SVC MB PVDDQ_CPU0_ABCD VR PROGRAM PART'                                | ''        
 'R3116-H0021-01'    = 'PRGM,FAB4,FS9K/SVC MB PVDDQ_CPU0_EFGH VR PROGRAM PART'                                | ''        
 'R3116-H0022-01'    = 'PRGM,FAB4,FS9K/SVC MB P0V8_PFX0 VR PROGRAM PART'                                      | ''        
 'R3116-H0023-01'    = 'PRGM,FAB4,FS9K/SVC MB PVCCIN_CPU1 VR PROGRAM PART'                                    | ''        
 'R3116-H0024-01'    = 'PRGM,FAB4,FS9K/SVC MB PVCCIO_CPU1 VR PROGRAM PART'                                    | ''        
 'R3116-H0025-01'    = 'PRGM,FAB4,FS9K/SVC MB PVDDQ_CPU1_JKLM VR PROGRAM PART'                                | ''        
 'R3116-H0026-01'    = 'PRGM,FAB4,FS9K/SVC MB PVDDQ_CPU1_PQRS VR PROGRAM PART'                                | ''        
 'R3116-H0027-01'    = 'PRGM,FAB4,FS9K/SVC MB P0V8_PFX1 VR PROGRAM PART'                                      | ''        
 'R3116-H0028-01'    = 'PRGM,FAB4,FS9K/SVC MB P0V8_PSX VR PROGRAM PART'                                       | ''        
 'R3135-G0001-03-SC' = 'SCH,R3135-G0001-03-SC,ARES RESPIN MB'                                                 | ''        
 'R3135-G0001-04-SC' = 'SCH,R3135-G0001-04-SC,ARES RESPIN MB FOR MULAN'                                       | ''        
 'R3135-G0002-02-SC' = 'SCH,R3135-G0002-02-SC,ARES RESPIN RISER CARD'                                         | ''        
 'R3135-G0005-02-SC' = 'SCH,R3135-G0005-02-SC,ARES RESPIN 1PPS&TOD BOARD'                                     | ''        
 'R3135-G0001-05-SC' = 'SCH,R3135-G0001-05-SC,ARES RESPIN MB FOR ZXE'                                         | ''        
 'R3116-E0408-01'    = 'MECH,MYLAR,FAB4 MB BOTTOM BACK MYLAR'                                                 | ''        
 'R3116-E0409-01'    = 'MECH,MYLAR,FAB4 MB BOTTOM FRONT MYLAR'                                                | ''        
 'R3042-G0001-02-SC' = 'SCH,IBM FAB3+_VE MOTHER BOARD SCHEMATIC'                                              | ''        
 'R3042-G0006-01-SC' = 'SCH,FAB3+_VE TPM CARD,SCHEMATIC'                                                      | ''        
 'R3224-H0002-01'    = 'PRGM,ARES_GEN2 BMC CODE'                                                              | ''        
 'R3224-H0001-01'    = 'PRGM,ARES_GEN2 BIOS CODE'                                                             | ''        
 'R3224-H0005-01'    = 'PRGM,ARES_GEN2 CPLD CODE'                                                             | ''        
 'R3224-H0006-01'    = 'PRGM,ARES_GEN2 RISER VPD'                                                             | ''        
 'R3224-H0004-01'    = 'PRGM,ARES_GEN2 I210 FIRMWARE'                                                         | ''        
 'R3224-H0003-01'    = 'PRGM,ARES_GEN2 I211 FIRMWARE'                                                         | ''        
 'R3224-H0007-01'    = 'PRGM,ARES_GEN2 MB VPD'                                                                | ''        
 'R3116-G0003-02-SC' = 'SCH,FAB4 FS9K DRIVE MIDPLANE SCHEMATIC'                                               | ''        
 'R3116-G0012-01-SC' = 'SCH,FAB4 BMC CARD SCHEMATIC'                                                          | ''        
 'R3116-G0011-01-SC' = 'SCH,FAB4 TPM CARD SCHEMATIC'                                                          | ''        
 'R3116-G0009-02-SC' = 'SCH,FAB4 M.2 ADAPTER BOARD SCHEMATIC'                                                 | ''        
 'R3116-G0007-02-SC' = 'SCH,FAB4 PCIE ADAPTER CARD BOARD SCHEMATIC'                                           | ''        
 'R3116-G0002-02-SC' = 'SCH,FAB4 SVC MB SCHEMATIC'                                                            | ''        
 'R3116-G0001-02-SC' = 'SCH,FAB4 FS9K MB SCHEMATIC'                                                           | ''        
 'R3116-H0029-01'    = 'PRGM,FAB4,BMC PROGRAM PART'                                                           | ''        
 'R3116-G0004-02-SC' = 'SCH,FAB4 SVC-H 2U MIDPLANE SCHEMATIC'                                                 | ''        
 'R3116-G0010-02-SC' = 'SCH,FAB4 BBU BACKPLANE SCHEMATIC'                                                     | ''        
 'R3137-G0001-03-SC' = 'SCH,TITAN SAS4 ESM PCBA SCHEMATIC,A3'                                                 | ''        
 'R3116-G0005-02-SC' = 'SCH,FAB4 FS9K PSU BACKPLANE SCHEMATIC'                                                | ''        
 'R3116-G0006-02-SC' = 'SCH,FAB4 SVC-H 2U PSU BACKPLANE'                                                      | ''        
 'R3116-G0008-02-SC' = 'SCH,FAB4 PIB SCHEMATIC'                                                               | ''        
 'R3116-E0167-02'    = 'MECH,MB TOP FOAM FOR THERMAL,FAB4'                                                    | ''        
 'R3116-E0402-02'    = 'MECH,MYLAR,FAB4 MB REAR 240V MYLAR'                                                   | ''        
 'R3116-E0401-02'    = 'MECH,MYLAR,FAB4 MB FRONT 240V MYLAR'                                                  | ''        
 'R3116-E0409-02'    = 'MECH,MYLAR,FAB4 MB BOTTOM FRONT MYLAR'                                                | ''        
 'R3116-E0408-02'    = 'MECH,MYLAR,FAB4 MB BOTTOM BACK MYLAR'                                                 | ''        
 'R3116-E0168-02'    = 'MECH,MB BOTTOM FOAM FOR THERMAL,FAB4'                                                 | ''        
 'R3116-E0446-01'    = 'MECH,FAB4 PCIE MYLAR'                                                                 | ''        
 'R3116-E0207-02'    = 'MECH,BP INSULATOR1 TOP1 FAB4 2U'                                                      | ''        
 'R3116-D0003-02'    = 'PLAST,MYLAR HDD BP TOP'                                                               | ''        
 'R3116-D0005-02'    = 'PLAST,MYLAR HDD BP BOTTOM'                                                            | ''        
 'R3116-D0004-02'    = 'PLAST,MYLAR HDD BP MID'                                                               | ''        
 'R3023-G0013-02-SC' = 'SCH,NEBULA GEN2 PASSTHROUGH CARD (WITH ASTERA RETIMER) SCHEMATIC'                     | ''        
 'R3224-H0008-01'    = 'PRGM,ARES_GEN2 U65 PVNN_NAC_PVCCANA FIRMWARE CODE'                                    | ''        
 'R3224-H0009-01'    = 'PRGM,ARES_GEN2 U59 PVCCIN FIRMWARE CODE'                                              | ''        
 'R3224-H0011-01'    = 'PRGM,ARES_GEN2 U78 VDDQ FIRMWARE CODE'                                                | ''        
 'R3224-H0010-01'    = 'PRGM,ARES_GEN2 U80 P1V05_PVNN_PCH FIRMWARE CODE'                                      | ''        
 'R3224-H0012-01'    = 'PRGM,ARES_GEN2 RISER VPD'                                                             | ''        
 'R3224-H0013-01'    = 'PRGM,ARES_GEN2 FAN VPD'                                                               | ''        
 'G350-10148-01'     = 'MECH,LGA4677 CARRIER -E1A W/O SHIM'                                                   | ''        
 'G350-10149-01'     = 'MECH,BOLSTER PLATE WITH SOCKET COVER,LGA4677'                                         | ''        
 'R3223-D0050-01'    = 'PLAST,FOAM,FOR LED SHADING'                                                           | ''        
 'R3222-H0001-01'    = 'PRGM,ESM,SES FLASH'                                                                   | ''        
 'R3222-H0002-01'    = 'PRGM,CPLD,CALLISTO CPLD'                                                              | ''        
 'R3222-H0003-01'    = 'PRGM,VPD,CALLISTO ESM'                                                                | ''        
 'R3222-H0004-01'    = 'PRGM,VPD,CALLISTO MID-PLANE'                                                          | ''        
 'R3222-G0001-01-SC' = 'DOC,CALLISTO ESM SCHEMATIC'                                                           | ''        
 'R3222-G0002-01-SC' = 'DOC,CALLISTO MID-PLANE SCHEMATIC'                                                     | ''        
 'R3222-G0003-01-SC' = 'DOC,CALLISTO PIB BOARD SCHEMATIC'                                                     | ''        
 'R3223-H0002-01'    = 'PRGM,CPLD,RAINBOW G2 CPLD'                                                            | ''        
 'R3223-H0001-01'    = 'PRGM,ESM,RAINBOW G2 SES FLASH'                                                        | ''        
 'R3223-H0003-01'    = 'PRGM,VPD,RAINBOW G2 ESM'                                                              | ''        
 'R3223-H0005-01'    = 'PRGM,BOOT MEMORY,RAONBOW G2 EXPANDER BOOT MEMORY'                                     | ''        
 'R3223-G0001-01-SC' = 'SCH,RAINBOW G2 ESM SCHEMATIC'                                                         | ''        
 'R3222-H0005-01'    = 'PRGM,SXP BOOT MEM'                                                                    | ''        
 'G350-10151-01'     = 'MECH,LGA4677 CARRIER -E1A (W/O SHIM,SP XCC)'                                          | ''        
 'G350-10152-01'     = 'MECH,BOLSTER PLATE WITH SOCKET COVER,CLIP WELDED,LGA4677'                             | ''        
 'G205-10040-01'     = 'CON,1X2 QSFP-DD (2X) TO TGA 2X,P1/P2 TO P5 LENGTH 265MM,P3/P4 TO P6 LENGTH 280MM,1X2 BIPASS CABLE ASSY'                 | ''        
 'G205-10041-01'     = 'CON,1X2 QSFP-DD (2X) TO TGA 2X,P1/P2 TO P5 LENGTH 265MM,P3/P4 TO P6 LENGTH 250MM,1X2 BIPASS CABLE ASSY'                 | ''        
 'G205-10042-01'     = 'CON,1X2 QSFP-DD (2X) TO TGA 2X,P1/P2 TO P5 LENGTH 185MM,P3/P4 TO P6 LENGTH 215MM,1X2 BIPASS CABLE ASSY'                 | ''        
 'G205-10043-01'     = 'CON,1X2 QSFP-DD (2X) TO TGA 2X,P1/P2 TO P5 LENGTH 250MM,P3/P4 TO P6 LENGTH 250MM,1X2 BIPASS CABLE ASSY'                 | ''        
 'G205-10044-01'     = 'CON,1X2 QSFP-DD (2X) TO TGA 2X,P1/P2 TO P5 LENGTH 100MM,P3/P4 TO P6 LENGTH 110MM,1X2 BIPASS CABLE ASSY'                 | ''        
 'G205-10045-01'     = 'CON,1X2 QSFP-DD (2X) TO TGA 2X,P1/P2 TO P5 LENGTH 100MM,P3/P4 TO P6 LENGTH 100MM,1X2 BIPASS CABLE ASSY'                 | ''        
 'G205-10046-01'     = 'CON,1X2 QSFP-DD (2X) TO TGA 2X,P1/P2 TO P5 LENGTH 110MM,P3/P4 TO P6 LENGTH 100MM,1X2 BIPASS CABLE ASSY'                 | ''        
 'G205-10047-01'     = 'CON,1X2 QSFP-DD (2X) TO TGA 2X,P1/P2 TO P5 LENGTH 215MM,P3/P4 TO P6 LENGTH 185MM,1X2 BIPASS CABLE ASSY'                 | ''        
 'R4004-G0001-01-SC' = 'SCH,ASTERIA ESM CARD SCHEMATIC,REV1.0'                                                                                  | ''        
 'R4001-H0003-01'    = 'PRGM,CARRERA MB CPLD CODE'                                                                                              | ''        
 'R4001-H0004-01'    = 'PRGM,CARRERA MB VPD CODE'                                                                                               | ''        
 'R4001-H0005-01'    = 'PRGM,CARRERA MP VPD CODE'                                                                                               | ''        
 'R4001-H0006-01'    = 'PRGM,CARRERA STG SWITCH CODE'                                                                                           | ''        
 'R4001-H0007-01'    = 'PRGM,CARRERA STG SW BOARD VPD CODE'                                                                                     | ''        
 'R4001-H0008-01'    = 'PRGM,CARRERA STG SW BOARD CPLD CODE'                                                                                    | ''        
 'R4001-H0009-01'    = 'PRGM,CARRERA STG BP VPD CODE'                                                                                           | ''        
 'R4001-H0010-01'    = 'PRGM,CARRERA IO SWITCH CODE'                                                                                            | ''        
 'R4001-H0011-01'    = 'PRGM,CARRERA IO SW BOARD CPLD CODE'                                                                                     | ''        
 'R4001-H0012-01'    = 'PRGM,CARRERA STG IO SW BOARD VPD CODE'                                                                                  | ''        
 'R4001-H0013-01'    = 'PRGM,CARRERA FP VPD CODE'                                                                                               | ''        
 'R4001-H0014-01'    = 'PRGM,CARRERA MB CPU0 PVCCIN&PVCCFA_FIVRA VRM CODE'                                                                      | ''        
 'R4001-H0015-01'    = 'PRGM,CARRERA MB CPU0 VCCINFAON&PVCCFA_EHV VRM CODE'                                                                     | ''        
 'R4001-H0016-01'    = 'PRGM,CARRERA MB CPU0 VCCD_HV VRM CODE'                                                                                  | ''        
 'R4001-H0017-01'    = 'PRGM,CARRERA MB CPU1 PVCCIN&PVCCFA_FIVRA VRM CODE'                                                                      | ''        
 'R4001-H0018-01'    = 'PRGM,CARRERA MB CPU1 VCCINFAON&PVCCFA_EHV VRM CODE'                                                                     | ''        
 'R4001-H0019-01'    = 'PRGM,CARRERA CPU1 MB VCCD_HV VRM CODE'                                                                                  | ''        
 'R4001-H0020-01'    = 'PRGM,CARRERA MB I210IS IMAGE CODE'                                                                                      | ''        
 'R4001-H0021-01'    = 'PRGM,CARRERA IO NODE X710-AT IMAGE CODE'                                                                                | ''        
 'R4001-H0002-01'    = 'PRGM,CARRERA BMC CODE'                                                                                                  | ''        
 'R4001-H0001-01'    = 'PRGM,CARRERA BIOS CODE'                                                                                                 | ''        

END_PART

END.

